(kicad_pcb
	(version 20260206)
	(generator "pcbnew")
	(generator_version "10.0")
	(general
		(thickness 1.6)
		(legacy_teardrops no)
	)
	(paper "A4")
	(title_block
		(title "01162023_DA0F0TEBIF0_F0T_Expander_BD_F_brd_V02_OCP.brd")
		(comment 1 "Grand Teton / footprints 4765-4770 of 9728")
	)
	(layers
		(0 "F.Cu" signal "TOP")
		(4 "In1.Cu" signal "GND")
		(6 "In2.Cu" signal "VCC")
		(8 "In3.Cu" signal "VCC1")
		(10 "In4.Cu" signal "GND1")
		(12 "In5.Cu" signal "IN1")
		(14 "In6.Cu" signal "GND2")
		(16 "In7.Cu" signal "IN2")
		(18 "In8.Cu" signal "GND3")
		(20 "In9.Cu" signal "IN3")
		(22 "In10.Cu" signal "GND4")
		(24 "In11.Cu" signal "IN4")
		(26 "In12.Cu" signal "GND5")
		(28 "In13.Cu" signal "IN5")
		(30 "In14.Cu" signal "GND6")
		(32 "In15.Cu" signal "IN6")
		(34 "In16.Cu" signal "GND7")
		(2 "B.Cu" signal "BOTTOM")
		(9 "F.Adhes" user "F.Adhesive")
		(11 "B.Adhes" user "B.Adhesive")
		(13 "F.Paste" user "Package Geometry/Pastemask Top")
		(15 "B.Paste" user "Package Geometry/Pastemask Bottom")
		(5 "F.SilkS" user "Ref Des/Silkscreen Top")
		(7 "B.SilkS" user "Ref Des/Silkscreen Bottom")
		(1 "F.Mask" user "Board Geometry/Soldermask Top")
		(3 "B.Mask" user "Board Geometry/Soldermask Bottom")
		(17 "Dwgs.User" user "User.Drawings")
		(19 "Cmts.User" user "User.Comments")
		(21 "Eco1.User" user "User.Eco1")
		(23 "Eco2.User" user "User.Eco2")
		(25 "Edge.Cuts" user "Board Geometry/Outline")
		(27 "Margin" user)
		(31 "F.CrtYd" user "Package Geometry/Place Bound Top")
		(29 "B.CrtYd" user "Package Geometry/Place Bound Bottom")
		(35 "F.Fab" user "Ref Des/Assembly Top")
		(33 "B.Fab" user "Ref Des/Assembly Bottom")
	)
	(footprint ""
		(layer "F.Cu")
		(at 254.227838 -35.876738)
		(property "Reference" "R6083"
			(at 0 0 0)
			(layer "F.SilkS")
			(hide yes)
			(effects
				(font
					(size 1.27 1.27)
				)
			)
		)
		(property "Value" ""
			(at 0 0 0)
			(layer "F.Fab")
			(effects
				(font
					(size 1.27 1.27)
				)
			)
		)
		(duplicate_pad_numbers_are_jumpers no)
		(fp_line
			(start -0.7874 -0.4064)
			(end 0.7874 -0.4064)
			(stroke
				(width 0.1524)
				(type default)
			)
			(layer "F.SilkS")
		)
		(fp_line
			(start -0.7874 0.4064)
			(end -0.7874 -0.4064)
			(stroke
				(width 0.1524)
				(type default)
			)
			(layer "F.SilkS")
		)
		(fp_line
			(start 0.7874 -0.4064)
			(end 0.7874 0.4064)
			(stroke
				(width 0.1524)
				(type default)
			)
			(layer "F.SilkS")
		)
		(fp_line
			(start 0.7874 0.4064)
			(end -0.7874 0.4064)
			(stroke
				(width 0.1524)
				(type default)
			)
			(layer "F.SilkS")
		)
		(fp_line
			(start -0.67945 -0.305054)
			(end -0.12065 -0.305054)
			(stroke
				(width 0.1)
				(type default)
			)
			(layer "F.Fab")
		)
		(fp_line
			(start -0.67945 0.3048)
			(end -0.67945 -0.305054)
			(stroke
				(width 0.1)
				(type default)
			)
			(layer "F.Fab")
		)
		(fp_line
			(start -0.12065 -0.305054)
			(end -0.12065 -0.2794)
			(stroke
				(width 0.1)
				(type default)
			)
			(layer "F.Fab")
		)
		(fp_line
			(start -0.12065 -0.2794)
			(end 0.12065 -0.2794)
			(stroke
				(width 0.1)
				(type default)
			)
			(layer "F.Fab")
		)
		(fp_line
			(start -0.12065 0.2794)
			(end -0.12065 0.3048)
			(stroke
				(width 0.1)
				(type default)
			)
			(layer "F.Fab")
		)
		(fp_line
			(start -0.12065 0.3048)
			(end -0.67945 0.3048)
			(stroke
				(width 0.1)
				(type default)
			)
			(layer "F.Fab")
		)
		(fp_line
			(start 0.120396 0.2794)
			(end -0.12065 0.2794)
			(stroke
				(width 0.1)
				(type default)
			)
			(layer "F.Fab")
		)
		(fp_line
			(start 0.120396 0.3048)
			(end 0.120396 0.2794)
			(stroke
				(width 0.1)
				(type default)
			)
			(layer "F.Fab")
		)
		(fp_line
			(start 0.12065 -0.3048)
			(end 0.67945 -0.3048)
			(stroke
				(width 0.1)
				(type default)
			)
			(layer "F.Fab")
		)
		(fp_line
			(start 0.12065 -0.2794)
			(end 0.12065 -0.3048)
			(stroke
				(width 0.1)
				(type default)
			)
			(layer "F.Fab")
		)
		(fp_line
			(start 0.67945 -0.3048)
			(end 0.67945 0.3048)
			(stroke
				(width 0.1)
				(type default)
			)
			(layer "F.Fab")
		)
		(fp_line
			(start 0.67945 0.3048)
			(end 0.120396 0.3048)
			(stroke
				(width 0.1)
				(type default)
			)
			(layer "F.Fab")
		)
		(pad "1" smd circle
			(at -0.40005 0)
			(size 0 0)
			(layers "F.Cu" "F.Mask" "F.Paste")
			(net "PWRGD_P3V3_SSD9_D")
		)
		(pad "2" smd circle
			(at 0.40005 0)
			(size 0 0)
			(layers "F.Cu" "F.Mask" "F.Paste")
			(net "PWRGD_P3V3_SSD9_R")
		)
	)
	(footprint ""
		(layer "F.Cu")
		(at 60.210954 -61.386974)
		(property "Reference" "R4491"
			(at 0 0 0)
			(layer "F.SilkS")
			(hide yes)
			(effects
				(font
					(size 1.27 1.27)
				)
			)
		)
		(property "Value" ""
			(at 0 0 0)
			(layer "F.Fab")
			(effects
				(font
					(size 1.27 1.27)
				)
			)
		)
		(duplicate_pad_numbers_are_jumpers no)
		(fp_line
			(start -0.7874 -0.4064)
			(end 0.7874 -0.4064)
			(stroke
				(width 0.1524)
				(type default)
			)
			(layer "F.SilkS")
		)
		(fp_line
			(start -0.7874 0.4064)
			(end -0.7874 -0.4064)
			(stroke
				(width 0.1524)
				(type default)
			)
			(layer "F.SilkS")
		)
		(fp_line
			(start 0.7874 -0.4064)
			(end 0.7874 0.4064)
			(stroke
				(width 0.1524)
				(type default)
			)
			(layer "F.SilkS")
		)
		(fp_line
			(start 0.7874 0.4064)
			(end -0.7874 0.4064)
			(stroke
				(width 0.1524)
				(type default)
			)
			(layer "F.SilkS")
		)
		(fp_line
			(start -0.67945 -0.305054)
			(end -0.12065 -0.305054)
			(stroke
				(width 0.1)
				(type default)
			)
			(layer "F.Fab")
		)
		(fp_line
			(start -0.67945 0.3048)
			(end -0.67945 -0.305054)
			(stroke
				(width 0.1)
				(type default)
			)
			(layer "F.Fab")
		)
		(fp_line
			(start -0.12065 -0.305054)
			(end -0.12065 -0.2794)
			(stroke
				(width 0.1)
				(type default)
			)
			(layer "F.Fab")
		)
		(fp_line
			(start -0.12065 -0.2794)
			(end 0.12065 -0.2794)
			(stroke
				(width 0.1)
				(type default)
			)
			(layer "F.Fab")
		)
		(fp_line
			(start -0.12065 0.2794)
			(end -0.12065 0.3048)
			(stroke
				(width 0.1)
				(type default)
			)
			(layer "F.Fab")
		)
		(fp_line
			(start -0.12065 0.3048)
			(end -0.67945 0.3048)
			(stroke
				(width 0.1)
				(type default)
			)
			(layer "F.Fab")
		)
		(fp_line
			(start 0.120396 0.2794)
			(end -0.12065 0.2794)
			(stroke
				(width 0.1)
				(type default)
			)
			(layer "F.Fab")
		)
		(fp_line
			(start 0.120396 0.3048)
			(end 0.120396 0.2794)
			(stroke
				(width 0.1)
				(type default)
			)
			(layer "F.Fab")
		)
		(fp_line
			(start 0.12065 -0.3048)
			(end 0.67945 -0.3048)
			(stroke
				(width 0.1)
				(type default)
			)
			(layer "F.Fab")
		)
		(fp_line
			(start 0.12065 -0.2794)
			(end 0.12065 -0.3048)
			(stroke
				(width 0.1)
				(type default)
			)
			(layer "F.Fab")
		)
		(fp_line
			(start 0.67945 -0.3048)
			(end 0.67945 0.3048)
			(stroke
				(width 0.1)
				(type default)
			)
			(layer "F.Fab")
		)
		(fp_line
			(start 0.67945 0.3048)
			(end 0.120396 0.3048)
			(stroke
				(width 0.1)
				(type default)
			)
			(layer "F.Fab")
		)
		(pad "1" smd circle
			(at -0.40005 0)
			(size 0 0)
			(layers "F.Cu" "F.Mask" "F.Paste")
			(net "PWRGD_P3V3_SSD2")
		)
		(pad "2" smd circle
			(at 0.40005 0)
			(size 0 0)
			(layers "F.Cu" "F.Mask" "F.Paste")
			(net "PWRGD_P3V3_SSD2_R")
		)
	)
	(footprint ""
		(layer "F.Cu")
		(at 98.17481 -48.753014 180)
		(property "Reference" "C207"
			(at 0 0 180)
			(layer "F.SilkS")
			(hide yes)
			(effects
				(font
					(size 1.27 1.27)
				)
			)
		)
		(property "Value" ""
			(at 0 0 180)
			(layer "F.Fab")
			(effects
				(font
					(size 1.27 1.27)
				)
			)
		)
		(duplicate_pad_numbers_are_jumpers no)
		(fp_line
			(start 0.7874 0.4064)
			(end -0.7874 0.4064)
			(stroke
				(width 0.1524)
				(type default)
			)
			(layer "F.SilkS")
		)
		(fp_line
			(start 0.7874 -0.4064)
			(end 0.7874 0.4064)
			(stroke
				(width 0.1524)
				(type default)
			)
			(layer "F.SilkS")
		)
		(fp_line
			(start -0.7874 0.4064)
			(end -0.7874 -0.4064)
			(stroke
				(width 0.1524)
				(type default)
			)
			(layer "F.SilkS")
		)
		(fp_line
			(start -0.7874 -0.4064)
			(end 0.7874 -0.4064)
			(stroke
				(width 0.1524)
				(type default)
			)
			(layer "F.SilkS")
		)
		(fp_line
			(start 0.67945 0.3048)
			(end 0.120396 0.3048)
			(stroke
				(width 0.1)
				(type default)
			)
			(layer "F.Fab")
		)
		(fp_line
			(start 0.67945 -0.3048)
			(end 0.67945 0.3048)
			(stroke
				(width 0.1)
				(type default)
			)
			(layer "F.Fab")
		)
		(fp_line
			(start 0.12065 -0.2794)
			(end 0.12065 -0.3048)
			(stroke
				(width 0.1)
				(type default)
			)
			(layer "F.Fab")
		)
		(fp_line
			(start 0.12065 -0.3048)
			(end 0.67945 -0.3048)
			(stroke
				(width 0.1)
				(type default)
			)
			(layer "F.Fab")
		)
		(fp_line
			(start 0.120396 0.3048)
			(end 0.120396 0.2794)
			(stroke
				(width 0.1)
				(type default)
			)
			(layer "F.Fab")
		)
		(fp_line
			(start 0.120396 0.2794)
			(end -0.12065 0.2794)
			(stroke
				(width 0.1)
				(type default)
			)
			(layer "F.Fab")
		)
		(fp_line
			(start -0.12065 0.3048)
			(end -0.67945 0.3048)
			(stroke
				(width 0.1)
				(type default)
			)
			(layer "F.Fab")
		)
		(fp_line
			(start -0.12065 0.2794)
			(end -0.12065 0.3048)
			(stroke
				(width 0.1)
				(type default)
			)
			(layer "F.Fab")
		)
		(fp_line
			(start -0.12065 -0.2794)
			(end 0.12065 -0.2794)
			(stroke
				(width 0.1)
				(type default)
			)
			(layer "F.Fab")
		)
		(fp_line
			(start -0.12065 -0.305054)
			(end -0.12065 -0.2794)
			(stroke
				(width 0.1)
				(type default)
			)
			(layer "F.Fab")
		)
		(fp_line
			(start -0.67945 0.3048)
			(end -0.67945 -0.305054)
			(stroke
				(width 0.1)
				(type default)
			)
			(layer "F.Fab")
		)
		(fp_line
			(start -0.67945 -0.305054)
			(end -0.12065 -0.305054)
			(stroke
				(width 0.1)
				(type default)
			)
			(layer "F.Fab")
		)
		(pad "1" smd circle
			(at -0.40005 0 180)
			(size 0 0)
			(layers "F.Cu" "F.Mask" "F.Paste")
			(net "P3V3_AUX")
		)
		(pad "2" smd circle
			(at 0.40005 0 180)
			(size 0 0)
			(layers "F.Cu" "F.Mask" "F.Paste")
			(net "GND")
		)
	)
	(footprint ""
		(layer "F.Cu")
		(at 374.543828 -45.88891)
		(property "Reference" "R641"
			(at 0 0 0)
			(layer "F.SilkS")
			(hide yes)
			(effects
				(font
					(size 1.27 1.27)
				)
			)
		)
		(property "Value" ""
			(at 0 0 0)
			(layer "F.Fab")
			(effects
				(font
					(size 1.27 1.27)
				)
			)
		)
		(duplicate_pad_numbers_are_jumpers no)
		(fp_line
			(start -0.7874 -0.4064)
			(end 0.7874 -0.4064)
			(stroke
				(width 0.1524)
				(type default)
			)
			(layer "F.SilkS")
		)
		(fp_line
			(start -0.7874 0.4064)
			(end -0.7874 -0.4064)
			(stroke
				(width 0.1524)
				(type default)
			)
			(layer "F.SilkS")
		)
		(fp_line
			(start 0.7874 -0.4064)
			(end 0.7874 0.4064)
			(stroke
				(width 0.1524)
				(type default)
			)
			(layer "F.SilkS")
		)
		(fp_line
			(start 0.7874 0.4064)
			(end -0.7874 0.4064)
			(stroke
				(width 0.1524)
				(type default)
			)
			(layer "F.SilkS")
		)
		(fp_line
			(start -0.67945 -0.305054)
			(end -0.12065 -0.305054)
			(stroke
				(width 0.1)
				(type default)
			)
			(layer "F.Fab")
		)
		(fp_line
			(start -0.67945 0.3048)
			(end -0.67945 -0.305054)
			(stroke
				(width 0.1)
				(type default)
			)
			(layer "F.Fab")
		)
		(fp_line
			(start -0.12065 -0.305054)
			(end -0.12065 -0.2794)
			(stroke
				(width 0.1)
				(type default)
			)
			(layer "F.Fab")
		)
		(fp_line
			(start -0.12065 -0.2794)
			(end 0.12065 -0.2794)
			(stroke
				(width 0.1)
				(type default)
			)
			(layer "F.Fab")
		)
		(fp_line
			(start -0.12065 0.2794)
			(end -0.12065 0.3048)
			(stroke
				(width 0.1)
				(type default)
			)
			(layer "F.Fab")
		)
		(fp_line
			(start -0.12065 0.3048)
			(end -0.67945 0.3048)
			(stroke
				(width 0.1)
				(type default)
			)
			(layer "F.Fab")
		)
		(fp_line
			(start 0.120396 0.2794)
			(end -0.12065 0.2794)
			(stroke
				(width 0.1)
				(type default)
			)
			(layer "F.Fab")
		)
		(fp_line
			(start 0.120396 0.3048)
			(end 0.120396 0.2794)
			(stroke
				(width 0.1)
				(type default)
			)
			(layer "F.Fab")
		)
		(fp_line
			(start 0.12065 -0.3048)
			(end 0.67945 -0.3048)
			(stroke
				(width 0.1)
				(type default)
			)
			(layer "F.Fab")
		)
		(fp_line
			(start 0.12065 -0.2794)
			(end 0.12065 -0.3048)
			(stroke
				(width 0.1)
				(type default)
			)
			(layer "F.Fab")
		)
		(fp_line
			(start 0.67945 -0.3048)
			(end 0.67945 0.3048)
			(stroke
				(width 0.1)
				(type default)
			)
			(layer "F.Fab")
		)
		(fp_line
			(start 0.67945 0.3048)
			(end 0.120396 0.3048)
			(stroke
				(width 0.1)
				(type default)
			)
			(layer "F.Fab")
		)
		(pad "1" smd circle
			(at -0.40005 0)
			(size 0 0)
			(layers "F.Cu" "F.Mask" "F.Paste")
			(net "SSD12_ADC_A0")
		)
		(pad "2" smd circle
			(at 0.40005 0)
			(size 0 0)
			(layers "F.Cu" "F.Mask" "F.Paste")
			(net "GND")
		)
	)
	(footprint ""
		(layer "F.Cu")
		(at 198.564246 -363.583728 180)
		(property "Reference" "PR33"
			(at 0 0 180)
			(layer "F.SilkS")
			(hide yes)
			(effects
				(font
					(size 1.27 1.27)
				)
			)
		)
		(property "Value" ""
			(at 0 0 180)
			(layer "F.Fab")
			(effects
				(font
					(size 1.27 1.27)
				)
			)
		)
		(duplicate_pad_numbers_are_jumpers no)
		(fp_line
			(start 0.7874 0.4064)
			(end -0.7874 0.4064)
			(stroke
				(width 0.1524)
				(type default)
			)
			(layer "F.SilkS")
		)
		(fp_line
			(start 0.7874 -0.4064)
			(end 0.7874 0.4064)
			(stroke
				(width 0.1524)
				(type default)
			)
			(layer "F.SilkS")
		)
		(fp_line
			(start -0.7874 0.4064)
			(end -0.7874 -0.4064)
			(stroke
				(width 0.1524)
				(type default)
			)
			(layer "F.SilkS")
		)
		(fp_line
			(start -0.7874 -0.4064)
			(end 0.7874 -0.4064)
			(stroke
				(width 0.1524)
				(type default)
			)
			(layer "F.SilkS")
		)
		(fp_line
			(start 0.67945 0.3048)
			(end 0.120396 0.3048)
			(stroke
				(width 0.1)
				(type default)
			)
			(layer "F.Fab")
		)
		(fp_line
			(start 0.67945 -0.3048)
			(end 0.67945 0.3048)
			(stroke
				(width 0.1)
				(type default)
			)
			(layer "F.Fab")
		)
		(fp_line
			(start 0.12065 -0.2794)
			(end 0.12065 -0.3048)
			(stroke
				(width 0.1)
				(type default)
			)
			(layer "F.Fab")
		)
		(fp_line
			(start 0.12065 -0.3048)
			(end 0.67945 -0.3048)
			(stroke
				(width 0.1)
				(type default)
			)
			(layer "F.Fab")
		)
		(fp_line
			(start 0.120396 0.3048)
			(end 0.120396 0.2794)
			(stroke
				(width 0.1)
				(type default)
			)
			(layer "F.Fab")
		)
		(fp_line
			(start 0.120396 0.2794)
			(end -0.12065 0.2794)
			(stroke
				(width 0.1)
				(type default)
			)
			(layer "F.Fab")
		)
		(fp_line
			(start -0.12065 0.3048)
			(end -0.67945 0.3048)
			(stroke
				(width 0.1)
				(type default)
			)
			(layer "F.Fab")
		)
		(fp_line
			(start -0.12065 0.2794)
			(end -0.12065 0.3048)
			(stroke
				(width 0.1)
				(type default)
			)
			(layer "F.Fab")
		)
		(fp_line
			(start -0.12065 -0.2794)
			(end 0.12065 -0.2794)
			(stroke
				(width 0.1)
				(type default)
			)
			(layer "F.Fab")
		)
		(fp_line
			(start -0.12065 -0.305054)
			(end -0.12065 -0.2794)
			(stroke
				(width 0.1)
				(type default)
			)
			(layer "F.Fab")
		)
		(fp_line
			(start -0.67945 0.3048)
			(end -0.67945 -0.305054)
			(stroke
				(width 0.1)
				(type default)
			)
			(layer "F.Fab")
		)
		(fp_line
			(start -0.67945 -0.305054)
			(end -0.12065 -0.305054)
			(stroke
				(width 0.1)
				(type default)
			)
			(layer "F.Fab")
		)
		(pad "1" smd circle
			(at -0.40005 0 180)
			(size 0 0)
			(layers "F.Cu" "F.Mask" "F.Paste")
			(net "HSC_IMON")
		)
		(pad "2" smd circle
			(at 0.40005 0 180)
			(size 0 0)
			(layers "F.Cu" "F.Mask" "F.Paste")
			(net "AGND_HSC")
		)
	)
	(footprint ""
		(layer "F.Cu")
		(at 14.907768 -154.510994)
		(property "Reference" "PC603"
			(at 0 0 0)
			(layer "F.SilkS")
			(hide yes)
			(effects
				(font
					(size 1.27 1.27)
				)
			)
		)
		(property "Value" ""
			(at 0 0 0)
			(layer "F.Fab")
			(effects
				(font
					(size 1.27 1.27)
				)
			)
		)
		(duplicate_pad_numbers_are_jumpers no)
		(fp_line
			(start -0.7874 -0.4064)
			(end 0.7874 -0.4064)
			(stroke
				(width 0.1524)
				(type default)
			)
			(layer "F.SilkS")
		)
		(fp_line
			(start -0.7874 0.4064)
			(end -0.7874 -0.4064)
			(stroke
				(width 0.1524)
				(type default)
			)
			(layer "F.SilkS")
		)
		(fp_line
			(start 0.7874 -0.4064)
			(end 0.7874 0.4064)
			(stroke
				(width 0.1524)
				(type default)
			)
			(layer "F.SilkS")
		)
		(fp_line
			(start 0.7874 0.4064)
			(end -0.7874 0.4064)
			(stroke
				(width 0.1524)
				(type default)
			)
			(layer "F.SilkS")
		)
		(fp_line
			(start -0.67945 -0.305054)
			(end -0.12065 -0.305054)
			(stroke
				(width 0.1)
				(type default)
			)
			(layer "F.Fab")
		)
		(fp_line
			(start -0.67945 0.3048)
			(end -0.67945 -0.305054)
			(stroke
				(width 0.1)
				(type default)
			)
			(layer "F.Fab")
		)
		(fp_line
			(start -0.12065 -0.305054)
			(end -0.12065 -0.2794)
			(stroke
				(width 0.1)
				(type default)
			)
			(layer "F.Fab")
		)
		(fp_line
			(start -0.12065 -0.2794)
			(end 0.12065 -0.2794)
			(stroke
				(width 0.1)
				(type default)
			)
			(layer "F.Fab")
		)
		(fp_line
			(start -0.12065 0.2794)
			(end -0.12065 0.3048)
			(stroke
				(width 0.1)
				(type default)
			)
			(layer "F.Fab")
		)
		(fp_line
			(start -0.12065 0.3048)
			(end -0.67945 0.3048)
			(stroke
				(width 0.1)
				(type default)
			)
			(layer "F.Fab")
		)
		(fp_line
			(start 0.120396 0.2794)
			(end -0.12065 0.2794)
			(stroke
				(width 0.1)
				(type default)
			)
			(layer "F.Fab")
		)
		(fp_line
			(start 0.120396 0.3048)
			(end 0.120396 0.2794)
			(stroke
				(width 0.1)
				(type default)
			)
			(layer "F.Fab")
		)
		(fp_line
			(start 0.12065 -0.3048)
			(end 0.67945 -0.3048)
			(stroke
				(width 0.1)
				(type default)
			)
			(layer "F.Fab")
		)
		(fp_line
			(start 0.12065 -0.2794)
			(end 0.12065 -0.3048)
			(stroke
				(width 0.1)
				(type default)
			)
			(layer "F.Fab")
		)
		(fp_line
			(start 0.67945 -0.3048)
			(end 0.67945 0.3048)
			(stroke
				(width 0.1)
				(type default)
			)
			(layer "F.Fab")
		)
		(fp_line
			(start 0.67945 0.3048)
			(end 0.120396 0.3048)
			(stroke
				(width 0.1)
				(type default)
			)
			(layer "F.Fab")
		)
		(pad "1" smd circle
			(at -0.40005 0)
			(size 0 0)
			(layers "F.Cu" "F.Mask" "F.Paste")
			(net "P12V_NIC0_R")
		)
		(pad "2" smd circle
			(at 0.40005 0)
			(size 0 0)
			(layers "F.Cu" "F.Mask" "F.Paste")
			(net "GND")
		)
	)
)
